# S9S_MB_2U (Grand Teton) — schematic netlist excerpt (pin names and nets, part order shuffled) for the footprints in the layout excerpt that follows; sources: Cadence DE-HDL packaged netlist, KiCad conversion of 03242023_DA0F0TMBIJ0_F0T_Motherboard_J_brd_V01_OCP.brd

Q143  BC847BPN  IC  pkg SOT363XB  page 122
  E1  = GND
  B1  = H_CPU0_MEMHOT_OUT_R
  C2  = H_CPU0_MEMHOT_OUT
  E2  = PVNN_TERM_CPU0
  B2  = H_CPU0_MEMHOT_OUT_VT_R_N
  C1  = H_CPU0_MEMHOT_OUT_VT_N

R3977  Q_RES  100K 1% CHIP  pkg 0402LF  page 192 : A = P3V3_AUX ; B = P3V3_E1S_FAULT_0

(kicad_pcb
	(version 20260206)
	(generator "pcbnew")
	(generator_version "10.0")
	(general
		(thickness 1.6)
		(legacy_teardrops no)
	)
	(paper "A4")
	(title_block
		(title "03242023_DA0F0TMBIJ0_F0T_Motherboard_J_brd_V01_OCP.brd")
		(comment 1 "Grand Teton / footprints 3916-3917 of 6105")
	)
	(layers
		(0 "F.Cu" signal "TOP")
		(4 "In1.Cu" signal "GND")
		(6 "In2.Cu" signal "IN1")
		(8 "In3.Cu" signal "GND1")
		(10 "In4.Cu" signal "IN2")
		(12 "In5.Cu" signal "GND2")
		(14 "In6.Cu" signal "IN3")
		(16 "In7.Cu" signal "GND3")
		(18 "In8.Cu" signal "VCC")
		(20 "In9.Cu" signal "VCC1")
		(22 "In10.Cu" signal "GND4")
		(24 "In11.Cu" signal "IN4")
		(26 "In12.Cu" signal "GND5")
		(28 "In13.Cu" signal "IN5")
		(30 "In14.Cu" signal "GND6")
		(32 "In15.Cu" signal "IN6")
		(34 "In16.Cu" signal "GND7")
		(2 "B.Cu" signal "BOTTOM")
		(9 "F.Adhes" user "F.Adhesive")
		(11 "B.Adhes" user "B.Adhesive")
		(13 "F.Paste" user "Package Geometry/Pastemask Top")
		(15 "B.Paste" user "Package Geometry/Pastemask Bottom")
		(5 "F.SilkS" user "Ref Des/Silkscreen Top")
		(7 "B.SilkS" user "Ref Des/Silkscreen Bottom")
		(1 "F.Mask" user "Board Geometry/Soldermask Top")
		(3 "B.Mask" user "Board Geometry/Soldermask Bottom")
		(17 "Dwgs.User" user "User.Drawings")
		(19 "Cmts.User" user "User.Comments")
		(21 "Eco1.User" user "User.Eco1")
		(23 "Eco2.User" user "User.Eco2")
		(25 "Edge.Cuts" user "Board Geometry/Outline")
		(27 "Margin" user)
		(31 "F.CrtYd" user "Package Geometry/Place Bound Top")
		(29 "B.CrtYd" user "Package Geometry/Place Bound Bottom")
		(35 "F.Fab" user "Ref Des/Assembly Top")
		(33 "B.Fab" user "Ref Des/Assembly Bottom")
	)
	(footprint ""
		(layer "F.Cu")
		(at 130.10388 -96.230948 -90)
		(property "Reference" "Q143"
			(at -2.479802 0.69088 0)
			(unlocked yes)
			(layer "F.SilkS")
			(effects
				(font
					(size 0.635 0.4064)
					(thickness 0.1524)
				)
			)
		)
		(property "Value" ""
			(at 0 0 270)
			(layer "F.Fab")
			(effects
				(font
					(size 1.27 1.27)
				)
			)
		)
		(duplicate_pad_numbers_are_jumpers no)
		(fp_line
			(start -1.376172 1.199896)
			(end -1.376172 -1.199896)
			(stroke
				(width 0.1524)
				(type default)
			)
			(layer "F.SilkS")
		)
		(fp_line
			(start 1.376172 1.199896)
			(end -1.376172 1.199896)
			(stroke
				(width 0.1524)
				(type default)
			)
			(layer "F.SilkS")
		)
		(fp_line
			(start 0 -0.762)
			(end 0.508 -1.199896)
			(stroke
				(width 0.1524)
				(type default)
			)
			(layer "F.SilkS")
		)
		(fp_line
			(start -1.376172 -1.199896)
			(end -0.508 -1.199896)
			(stroke
				(width 0.1524)
				(type default)
			)
			(layer "F.SilkS")
		)
		(fp_line
			(start -0.508 -1.199896)
			(end 0 -0.762)
			(stroke
				(width 0.1524)
				(type default)
			)
			(layer "F.SilkS")
		)
		(fp_line
			(start 0.508 -1.199896)
			(end 1.376172 -1.199896)
			(stroke
				(width 0.1524)
				(type default)
			)
			(layer "F.SilkS")
		)
		(fp_line
			(start 1.376172 -1.199896)
			(end 1.376172 1.199896)
			(stroke
				(width 0.1524)
				(type default)
			)
			(layer "F.SilkS")
		)
		(fp_poly
			(pts
				(xy -1.5875 -0.8763) (xy -2.3495 -1.2573) (xy -2.3495 -0.4953)
			)
			(stroke
				(width 0)
				(type default)
			)
			(fill yes)
			(layer "F.SilkS")
		)
		(fp_line
			(start -0.674878 1.100074)
			(end -0.674878 -1.100074)
			(stroke
				(width 0.1)
				(type default)
			)
			(layer "F.Fab")
		)
		(fp_line
			(start 0.674878 1.100074)
			(end -0.674878 1.100074)
			(stroke
				(width 0.1)
				(type default)
			)
			(layer "F.Fab")
		)
		(fp_line
			(start -0.674878 -1.100074)
			(end 0.674878 -1.100074)
			(stroke
				(width 0.1)
				(type default)
			)
			(layer "F.Fab")
		)
		(fp_line
			(start 0.674878 -1.100074)
			(end 0.674878 1.100074)
			(stroke
				(width 0.1)
				(type default)
			)
			(layer "F.Fab")
		)
		(fp_poly
			(pts
				(xy -1.4605 -0.7493) (xy -2.2225 -1.1303) (xy -2.2225 -0.3683)
			)
			(stroke
				(width 0)
				(type default)
			)
			(fill yes)
			(layer "F.Fab")
		)
		(pad "1" smd rect
			(at -0.899922 -0.750062 180)
			(size 0.6096 0.6096)
			(layers "F.Cu" "F.Mask" "F.Paste")
			(net "GND")
		)
		(pad "2" smd rect
			(at -0.899922 0 180)
			(size 0.4064 0.6096)
			(layers "F.Cu" "F.Mask" "F.Paste")
			(net "H_CPU0_MEMHOT_OUT_R")
		)
		(pad "3" smd rect
			(at -0.899922 0.750062 180)
			(size 0.6096 0.6096)
			(layers "F.Cu" "F.Mask" "F.Paste")
			(net "H_CPU0_MEMHOT_OUT")
		)
		(pad "4" smd rect
			(at 0.899922 0.750062 180)
			(size 0.6096 0.6096)
			(layers "F.Cu" "F.Mask" "F.Paste")
			(net "PVNN_TERM_CPU0")
		)
		(pad "5" smd rect
			(at 0.899922 0 180)
			(size 0.4064 0.6096)
			(layers "F.Cu" "F.Mask" "F.Paste")
			(net "H_CPU0_MEMHOT_OUT_VT_R_N")
		)
		(pad "6" smd rect
			(at 0.899922 -0.750062 180)
			(size 0.6096 0.6096)
			(layers "F.Cu" "F.Mask" "F.Paste")
			(net "H_CPU0_MEMHOT_OUT_VT_N")
		)
	)
	(footprint ""
		(layer "F.Cu")
		(at 225.171762 -71.192898 90)
		(property "Reference" "R3977"
			(at 0 0 90)
			(layer "F.SilkS")
			(hide yes)
			(effects
				(font
					(size 1.27 1.27)
				)
			)
		)
		(property "Value" ""
			(at 0 0 90)
			(layer "F.Fab")
			(effects
				(font
					(size 1.27 1.27)
				)
			)
		)
		(duplicate_pad_numbers_are_jumpers no)
		(fp_line
			(start 0.7874 -0.4064)
			(end 0.7874 0.4064)
			(stroke
				(width 0.1524)
				(type default)
			)
			(layer "F.SilkS")
		)
		(fp_line
			(start -0.7874 -0.4064)
			(end 0.7874 -0.4064)
			(stroke
				(width 0.1524)
				(type default)
			)
			(layer "F.SilkS")
		)
		(fp_line
			(start 0.7874 0.4064)
			(end -0.7874 0.4064)
			(stroke
				(width 0.1524)
				(type default)
			)
			(layer "F.SilkS")
		)
		(fp_line
			(start -0.7874 0.4064)
			(end -0.7874 -0.4064)
			(stroke
				(width 0.1524)
				(type default)
			)
			(layer "F.SilkS")
		)
		(fp_line
			(start -0.12065 -0.305054)
			(end -0.12065 -0.2794)
			(stroke
				(width 0.1)
				(type default)
			)
			(layer "F.Fab")
		)
		(fp_line
			(start -0.67945 -0.305054)
			(end -0.12065 -0.305054)
			(stroke
				(width 0.1)
				(type default)
			)
			(layer "F.Fab")
		)
		(fp_line
			(start 0.67945 -0.3048)
			(end 0.67945 0.3048)
			(stroke
				(width 0.1)
				(type default)
			)
			(layer "F.Fab")
		)
		(fp_line
			(start 0.12065 -0.3048)
			(end 0.67945 -0.3048)
			(stroke
				(width 0.1)
				(type default)
			)
			(layer "F.Fab")
		)
		(fp_line
			(start 0.12065 -0.2794)
			(end 0.12065 -0.3048)
			(stroke
				(width 0.1)
				(type default)
			)
			(layer "F.Fab")
		)
		(fp_line
			(start -0.12065 -0.2794)
			(end 0.12065 -0.2794)
			(stroke
				(width 0.1)
				(type default)
			)
			(layer "F.Fab")
		)
		(fp_line
			(start 0.120396 0.2794)
			(end -0.12065 0.2794)
			(stroke
				(width 0.1)
				(type default)
			)
			(layer "F.Fab")
		)
		(fp_line
			(start -0.12065 0.2794)
			(end -0.12065 0.3048)
			(stroke
				(width 0.1)
				(type default)
			)
			(layer "F.Fab")
		)
		(fp_line
			(start 0.67945 0.3048)
			(end 0.120396 0.3048)
			(stroke
				(width 0.1)
				(type default)
			)
			(layer "F.Fab")
		)
		(fp_line
			(start 0.120396 0.3048)
			(end 0.120396 0.2794)
			(stroke
				(width 0.1)
				(type default)
			)
			(layer "F.Fab")
		)
		(fp_line
			(start -0.12065 0.3048)
			(end -0.67945 0.3048)
			(stroke
				(width 0.1)
				(type default)
			)
			(layer "F.Fab")
		)
		(fp_line
			(start -0.67945 0.3048)
			(end -0.67945 -0.305054)
			(stroke
				(width 0.1)
				(type default)
			)
			(layer "F.Fab")
		)
		(pad "1" smd circle
			(at -0.40005 0 90)
			(size 0 0)
			(layers "F.Cu" "F.Mask" "F.Paste")
			(net "P3V3_AUX")
		)
		(pad "2" smd circle
			(at 0.40005 0 90)
			(size 0 0)
			(layers "F.Cu" "F.Mask" "F.Paste")
			(net "P3V3_E1S_FAULT_0")
		)
	)
)
